# S9S_MB_2U (Grand Teton) — schematic netlist excerpt (pin names and nets, part order shuffled) for the footprints in the layout excerpt that follows; sources: Cadence DE-HDL packaged netlist, KiCad conversion of 03242023_DA0F0TMBIJ0_F0T_Motherboard_J_brd_V01_OCP.brd

R4197  Q_RES  1K 1% CHIP  pkg 0402LF  page 170 : A = U271_1_ADD1 ; B = GND
R2968  Q_RES  0 5% CHIP  pkg 0402LF  page 231 : A = SMB_PCIE0_3V3AUX_SDA_R3 ; B = SMB_SENSOR_M2_P0_3V3AUX_SDA

(kicad_pcb
	(version 20260206)
	(generator "pcbnew")
	(generator_version "10.0")
	(general
		(thickness 1.6)
		(legacy_teardrops no)
	)
	(paper "A4")
	(title_block
		(title "03242023_DA0F0TMBIJ0_F0T_Motherboard_J_brd_V01_OCP.brd")
		(comment 1 "Grand Teton / footprints 2614-2615 of 6105")
	)
	(layers
		(0 "F.Cu" signal "TOP")
		(4 "In1.Cu" signal "GND")
		(6 "In2.Cu" signal "IN1")
		(8 "In3.Cu" signal "GND1")
		(10 "In4.Cu" signal "IN2")
		(12 "In5.Cu" signal "GND2")
		(14 "In6.Cu" signal "IN3")
		(16 "In7.Cu" signal "GND3")
		(18 "In8.Cu" signal "VCC")
		(20 "In9.Cu" signal "VCC1")
		(22 "In10.Cu" signal "GND4")
		(24 "In11.Cu" signal "IN4")
		(26 "In12.Cu" signal "GND5")
		(28 "In13.Cu" signal "IN5")
		(30 "In14.Cu" signal "GND6")
		(32 "In15.Cu" signal "IN6")
		(34 "In16.Cu" signal "GND7")
		(2 "B.Cu" signal "BOTTOM")
		(9 "F.Adhes" user "F.Adhesive")
		(11 "B.Adhes" user "B.Adhesive")
		(13 "F.Paste" user "Package Geometry/Pastemask Top")
		(15 "B.Paste" user "Package Geometry/Pastemask Bottom")
		(5 "F.SilkS" user "Ref Des/Silkscreen Top")
		(7 "B.SilkS" user "Ref Des/Silkscreen Bottom")
		(1 "F.Mask" user "Board Geometry/Soldermask Top")
		(3 "B.Mask" user "Board Geometry/Soldermask Bottom")
		(17 "Dwgs.User" user "User.Drawings")
		(19 "Cmts.User" user "User.Comments")
		(21 "Eco1.User" user "User.Eco1")
		(23 "Eco2.User" user "User.Eco2")
		(25 "Edge.Cuts" user "Board Geometry/Outline")
		(27 "Margin" user)
		(31 "F.CrtYd" user "Package Geometry/Place Bound Top")
		(29 "B.CrtYd" user "Package Geometry/Place Bound Bottom")
		(35 "F.Fab" user "Ref Des/Assembly Top")
		(33 "B.Fab" user "Ref Des/Assembly Bottom")
	)
	(footprint ""
		(layer "F.Cu")
		(at 113.494312 -131.440682 180)
		(property "Reference" "R2968"
			(at 0 0 180)
			(layer "F.SilkS")
			(hide yes)
			(effects
				(font
					(size 1.27 1.27)
				)
			)
		)
		(property "Value" ""
			(at 0 0 180)
			(layer "F.Fab")
			(effects
				(font
					(size 1.27 1.27)
				)
			)
		)
		(duplicate_pad_numbers_are_jumpers no)
		(fp_line
			(start 0.7874 0.4064)
			(end -0.7874 0.4064)
			(stroke
				(width 0.1524)
				(type default)
			)
			(layer "F.SilkS")
		)
		(fp_line
			(start 0.7874 -0.4064)
			(end 0.7874 0.4064)
			(stroke
				(width 0.1524)
				(type default)
			)
			(layer "F.SilkS")
		)
		(fp_line
			(start -0.7874 0.4064)
			(end -0.7874 -0.4064)
			(stroke
				(width 0.1524)
				(type default)
			)
			(layer "F.SilkS")
		)
		(fp_line
			(start -0.7874 -0.4064)
			(end 0.7874 -0.4064)
			(stroke
				(width 0.1524)
				(type default)
			)
			(layer "F.SilkS")
		)
		(fp_line
			(start 0.67945 0.3048)
			(end 0.120396 0.3048)
			(stroke
				(width 0.1)
				(type default)
			)
			(layer "F.Fab")
		)
		(fp_line
			(start 0.67945 -0.3048)
			(end 0.67945 0.3048)
			(stroke
				(width 0.1)
				(type default)
			)
			(layer "F.Fab")
		)
		(fp_line
			(start 0.12065 -0.2794)
			(end 0.12065 -0.3048)
			(stroke
				(width 0.1)
				(type default)
			)
			(layer "F.Fab")
		)
		(fp_line
			(start 0.12065 -0.3048)
			(end 0.67945 -0.3048)
			(stroke
				(width 0.1)
				(type default)
			)
			(layer "F.Fab")
		)
		(fp_line
			(start 0.120396 0.3048)
			(end 0.120396 0.2794)
			(stroke
				(width 0.1)
				(type default)
			)
			(layer "F.Fab")
		)
		(fp_line
			(start 0.120396 0.2794)
			(end -0.12065 0.2794)
			(stroke
				(width 0.1)
				(type default)
			)
			(layer "F.Fab")
		)
		(fp_line
			(start -0.12065 0.3048)
			(end -0.67945 0.3048)
			(stroke
				(width 0.1)
				(type default)
			)
			(layer "F.Fab")
		)
		(fp_line
			(start -0.12065 0.2794)
			(end -0.12065 0.3048)
			(stroke
				(width 0.1)
				(type default)
			)
			(layer "F.Fab")
		)
		(fp_line
			(start -0.12065 -0.2794)
			(end 0.12065 -0.2794)
			(stroke
				(width 0.1)
				(type default)
			)
			(layer "F.Fab")
		)
		(fp_line
			(start -0.12065 -0.305054)
			(end -0.12065 -0.2794)
			(stroke
				(width 0.1)
				(type default)
			)
			(layer "F.Fab")
		)
		(fp_line
			(start -0.67945 0.3048)
			(end -0.67945 -0.305054)
			(stroke
				(width 0.1)
				(type default)
			)
			(layer "F.Fab")
		)
		(fp_line
			(start -0.67945 -0.305054)
			(end -0.12065 -0.305054)
			(stroke
				(width 0.1)
				(type default)
			)
			(layer "F.Fab")
		)
		(pad "1" smd circle
			(at -0.40005 0 180)
			(size 0 0)
			(layers "F.Cu" "F.Mask" "F.Paste")
			(net "SMB_PCIE0_3V3AUX_SDA_R3")
		)
		(pad "2" smd circle
			(at 0.40005 0 180)
			(size 0 0)
			(layers "F.Cu" "F.Mask" "F.Paste")
			(net "SMB_SENSOR_M2_P0_3V3AUX_SDA")
		)
	)
	(footprint ""
		(layer "F.Cu")
		(at 300.754034 -15.572994)
		(property "Reference" "R4197"
			(at 0 0 0)
			(layer "F.SilkS")
			(hide yes)
			(effects
				(font
					(size 1.27 1.27)
				)
			)
		)
		(property "Value" ""
			(at 0 0 0)
			(layer "F.Fab")
			(effects
				(font
					(size 1.27 1.27)
				)
			)
		)
		(duplicate_pad_numbers_are_jumpers no)
		(fp_line
			(start -0.7874 -0.4064)
			(end 0.7874 -0.4064)
			(stroke
				(width 0.1524)
				(type default)
			)
			(layer "F.SilkS")
		)
		(fp_line
			(start -0.7874 0.4064)
			(end -0.7874 -0.4064)
			(stroke
				(width 0.1524)
				(type default)
			)
			(layer "F.SilkS")
		)
		(fp_line
			(start 0.7874 -0.4064)
			(end 0.7874 0.4064)
			(stroke
				(width 0.1524)
				(type default)
			)
			(layer "F.SilkS")
		)
		(fp_line
			(start 0.7874 0.4064)
			(end -0.7874 0.4064)
			(stroke
				(width 0.1524)
				(type default)
			)
			(layer "F.SilkS")
		)
		(fp_line
			(start -0.67945 -0.305054)
			(end -0.12065 -0.305054)
			(stroke
				(width 0.1)
				(type default)
			)
			(layer "F.Fab")
		)
		(fp_line
			(start -0.67945 0.3048)
			(end -0.67945 -0.305054)
			(stroke
				(width 0.1)
				(type default)
			)
			(layer "F.Fab")
		)
		(fp_line
			(start -0.12065 -0.305054)
			(end -0.12065 -0.2794)
			(stroke
				(width 0.1)
				(type default)
			)
			(layer "F.Fab")
		)
		(fp_line
			(start -0.12065 -0.2794)
			(end 0.12065 -0.2794)
			(stroke
				(width 0.1)
				(type default)
			)
			(layer "F.Fab")
		)
		(fp_line
			(start -0.12065 0.2794)
			(end -0.12065 0.3048)
			(stroke
				(width 0.1)
				(type default)
			)
			(layer "F.Fab")
		)
		(fp_line
			(start -0.12065 0.3048)
			(end -0.67945 0.3048)
			(stroke
				(width 0.1)
				(type default)
			)
			(layer "F.Fab")
		)
		(fp_line
			(start 0.120396 0.2794)
			(end -0.12065 0.2794)
			(stroke
				(width 0.1)
				(type default)
			)
			(layer "F.Fab")
		)
		(fp_line
			(start 0.120396 0.3048)
			(end 0.120396 0.2794)
			(stroke
				(width 0.1)
				(type default)
			)
			(layer "F.Fab")
		)
		(fp_line
			(start 0.12065 -0.3048)
			(end 0.67945 -0.3048)
			(stroke
				(width 0.1)
				(type default)
			)
			(layer "F.Fab")
		)
		(fp_line
			(start 0.12065 -0.2794)
			(end 0.12065 -0.3048)
			(stroke
				(width 0.1)
				(type default)
			)
			(layer "F.Fab")
		)
		(fp_line
			(start 0.67945 -0.3048)
			(end 0.67945 0.3048)
			(stroke
				(width 0.1)
				(type default)
			)
			(layer "F.Fab")
		)
		(fp_line
			(start 0.67945 0.3048)
			(end 0.120396 0.3048)
			(stroke
				(width 0.1)
				(type default)
			)
			(layer "F.Fab")
		)
		(pad "1" smd circle
			(at -0.40005 0)
			(size 0 0)
			(layers "F.Cu" "F.Mask" "F.Paste")
			(net "U271_1_ADD1")
		)
		(pad "2" smd circle
			(at 0.40005 0)
			(size 0 0)
			(layers "F.Cu" "F.Mask" "F.Paste")
			(net "GND")
		)
	)
)
